# T6G (Grand Teton) — schematic netlist excerpt (pin names and nets, part order shuffled) for the footprints in the layout excerpt that follows; sources: Cadence DE-HDL packaged netlist, KiCad conversion of 04192023_DAF0TMB3IC0_F0TG_MB_C_brd_V02_OCP.brd

R1263  Q_RES  0 5% CHIP  pkg 0402LF  page 258 : A = P5V_AUX_ADC ; B = P5V_AUX_ADC_TIC
C634  Q_CAP  22UF 4V 20% X6S  pkg C0402  page 290 : A = P0V9_CPU0_RT1_2A ; B = GND

(kicad_pcb
	(version 20260206)
	(generator "pcbnew")
	(generator_version "10.0")
	(general
		(thickness 1.6)
		(legacy_teardrops no)
	)
	(paper "A4")
	(title_block
		(title "04192023_DAF0TMB3IC0_F0TG_MB_C_brd_V02_OCP.brd")
		(comment 1 "Grand Teton / footprints 6229-6230 of 8354")
	)
	(layers
		(0 "F.Cu" signal "TOP")
		(4 "In1.Cu" signal "GND")
		(6 "In2.Cu" signal "IN1")
		(8 "In3.Cu" signal "GND1")
		(10 "In4.Cu" signal "IN2")
		(12 "In5.Cu" signal "GND2")
		(14 "In6.Cu" signal "IN3")
		(16 "In7.Cu" signal "GND3")
		(18 "In8.Cu" signal "VCC")
		(20 "In9.Cu" signal "VCC1")
		(22 "In10.Cu" signal "GND4")
		(24 "In11.Cu" signal "IN4")
		(26 "In12.Cu" signal "GND5")
		(28 "In13.Cu" signal "IN5")
		(30 "In14.Cu" signal "GND6")
		(32 "In15.Cu" signal "IN6")
		(34 "In16.Cu" signal "GND7")
		(2 "B.Cu" signal "BOTTOM")
		(9 "F.Adhes" user "F.Adhesive")
		(11 "B.Adhes" user "B.Adhesive")
		(13 "F.Paste" user "Package Geometry/Pastemask Top")
		(15 "B.Paste" user "Package Geometry/Pastemask Bottom")
		(5 "F.SilkS" user "Ref Des/Silkscreen Top")
		(7 "B.SilkS" user "Ref Des/Silkscreen Bottom")
		(1 "F.Mask" user "Board Geometry/Soldermask Top")
		(3 "B.Mask" user "Board Geometry/Soldermask Bottom")
		(17 "Dwgs.User" user "User.Drawings")
		(19 "Cmts.User" user "User.Comments")
		(21 "Eco1.User" user "User.Eco1")
		(23 "Eco2.User" user "User.Eco2")
		(25 "Edge.Cuts" user "Board Geometry/Outline")
		(27 "Margin" user)
		(31 "F.CrtYd" user "Package Geometry/Place Bound Top")
		(29 "B.CrtYd" user "Package Geometry/Place Bound Bottom")
		(35 "F.Fab" user "Ref Des/Assembly Top")
		(33 "B.Fab" user "Ref Des/Assembly Bottom")
	)
	(footprint ""
		(layer "B.Cu")
		(at 231.114092 -321.775582)
		(property "Reference" "R1263"
			(at 0 0 0)
			(layer "B.SilkS")
			(hide yes)
			(effects
				(font
					(size 1.27 1.27)
				)
				(justify mirror)
			)
		)
		(property "Value" ""
			(at 0 0 0)
			(layer "B.Fab")
			(effects
				(font
					(size 1.27 1.27)
				)
				(justify mirror)
			)
		)
		(duplicate_pad_numbers_are_jumpers no)
		(fp_line
			(start -0.7874 -0.4064)
			(end -0.7874 0.4064)
			(stroke
				(width 0.1524)
				(type default)
			)
			(layer "B.SilkS")
		)
		(fp_line
			(start -0.7874 0.4064)
			(end 0.7874 0.4064)
			(stroke
				(width 0.1524)
				(type default)
			)
			(layer "B.SilkS")
		)
		(fp_line
			(start 0.7874 -0.4064)
			(end -0.7874 -0.4064)
			(stroke
				(width 0.1524)
				(type default)
			)
			(layer "B.SilkS")
		)
		(fp_line
			(start 0.7874 0.4064)
			(end 0.7874 -0.4064)
			(stroke
				(width 0.1524)
				(type default)
			)
			(layer "B.SilkS")
		)
		(fp_line
			(start -0.67945 -0.3048)
			(end -0.67945 0.3048)
			(stroke
				(width 0.1)
				(type default)
			)
			(layer "B.Fab")
		)
		(fp_line
			(start -0.67945 0.3048)
			(end -0.120396 0.3048)
			(stroke
				(width 0.1)
				(type default)
			)
			(layer "B.Fab")
		)
		(fp_line
			(start -0.12065 -0.3048)
			(end -0.67945 -0.3048)
			(stroke
				(width 0.1)
				(type default)
			)
			(layer "B.Fab")
		)
		(fp_line
			(start -0.12065 -0.2794)
			(end -0.12065 -0.3048)
			(stroke
				(width 0.1)
				(type default)
			)
			(layer "B.Fab")
		)
		(fp_line
			(start -0.120396 0.2794)
			(end 0.12065 0.2794)
			(stroke
				(width 0.1)
				(type default)
			)
			(layer "B.Fab")
		)
		(fp_line
			(start -0.120396 0.3048)
			(end -0.120396 0.2794)
			(stroke
				(width 0.1)
				(type default)
			)
			(layer "B.Fab")
		)
		(fp_line
			(start 0.12065 -0.305054)
			(end 0.12065 -0.2794)
			(stroke
				(width 0.1)
				(type default)
			)
			(layer "B.Fab")
		)
		(fp_line
			(start 0.12065 -0.2794)
			(end -0.12065 -0.2794)
			(stroke
				(width 0.1)
				(type default)
			)
			(layer "B.Fab")
		)
		(fp_line
			(start 0.12065 0.2794)
			(end 0.12065 0.3048)
			(stroke
				(width 0.1)
				(type default)
			)
			(layer "B.Fab")
		)
		(fp_line
			(start 0.12065 0.3048)
			(end 0.67945 0.3048)
			(stroke
				(width 0.1)
				(type default)
			)
			(layer "B.Fab")
		)
		(fp_line
			(start 0.67945 -0.305054)
			(end 0.12065 -0.305054)
			(stroke
				(width 0.1)
				(type default)
			)
			(layer "B.Fab")
		)
		(fp_line
			(start 0.67945 0.3048)
			(end 0.67945 -0.305054)
			(stroke
				(width 0.1)
				(type default)
			)
			(layer "B.Fab")
		)
		(pad "1" smd rect
			(at 0.40005 0)
			(size 0.4572 0.508)
			(layers "B.Cu" "B.Mask" "B.Paste")
			(net "P5V_AUX_ADC")
		)
		(pad "2" smd rect
			(at -0.40005 0)
			(size 0.4572 0.508)
			(layers "B.Cu" "B.Mask" "B.Paste")
			(net "P5V_AUX_ADC_TIC")
		)
	)
	(footprint ""
		(layer "B.Cu")
		(at 337.118706 -398.942052 90)
		(property "Reference" "C634"
			(at 0 0 90)
			(layer "B.SilkS")
			(hide yes)
			(effects
				(font
					(size 1.27 1.27)
				)
				(justify mirror)
			)
		)
		(property "Value" ""
			(at 0 0 90)
			(layer "B.Fab")
			(effects
				(font
					(size 1.27 1.27)
				)
				(justify mirror)
			)
		)
		(duplicate_pad_numbers_are_jumpers no)
		(fp_line
			(start 0.7874 -0.4064)
			(end -0.7874 -0.4064)
			(stroke
				(width 0.1524)
				(type default)
			)
			(layer "B.SilkS")
		)
		(fp_line
			(start -0.7874 -0.4064)
			(end -0.7874 0.4064)
			(stroke
				(width 0.1524)
				(type default)
			)
			(layer "B.SilkS")
		)
		(fp_line
			(start 0.7874 0.4064)
			(end 0.7874 -0.4064)
			(stroke
				(width 0.1524)
				(type default)
			)
			(layer "B.SilkS")
		)
		(fp_line
			(start -0.7874 0.4064)
			(end 0.7874 0.4064)
			(stroke
				(width 0.1524)
				(type default)
			)
			(layer "B.SilkS")
		)
		(fp_line
			(start 0.67945 -0.305054)
			(end 0.12065 -0.305054)
			(stroke
				(width 0.1)
				(type default)
			)
			(layer "B.Fab")
		)
		(fp_line
			(start 0.12065 -0.305054)
			(end 0.12065 -0.2794)
			(stroke
				(width 0.1)
				(type default)
			)
			(layer "B.Fab")
		)
		(fp_line
			(start -0.12065 -0.3048)
			(end -0.67945 -0.3048)
			(stroke
				(width 0.1)
				(type default)
			)
			(layer "B.Fab")
		)
		(fp_line
			(start -0.67945 -0.3048)
			(end -0.67945 0.3048)
			(stroke
				(width 0.1)
				(type default)
			)
			(layer "B.Fab")
		)
		(fp_line
			(start 0.12065 -0.2794)
			(end -0.12065 -0.2794)
			(stroke
				(width 0.1)
				(type default)
			)
			(layer "B.Fab")
		)
		(fp_line
			(start -0.12065 -0.2794)
			(end -0.12065 -0.3048)
			(stroke
				(width 0.1)
				(type default)
			)
			(layer "B.Fab")
		)
		(fp_line
			(start 0.12065 0.2794)
			(end 0.12065 0.3048)
			(stroke
				(width 0.1)
				(type default)
			)
			(layer "B.Fab")
		)
		(fp_line
			(start -0.120396 0.2794)
			(end 0.12065 0.2794)
			(stroke
				(width 0.1)
				(type default)
			)
			(layer "B.Fab")
		)
		(fp_line
			(start 0.67945 0.3048)
			(end 0.67945 -0.305054)
			(stroke
				(width 0.1)
				(type default)
			)
			(layer "B.Fab")
		)
		(fp_line
			(start 0.12065 0.3048)
			(end 0.67945 0.3048)
			(stroke
				(width 0.1)
				(type default)
			)
			(layer "B.Fab")
		)
		(fp_line
			(start -0.120396 0.3048)
			(end -0.120396 0.2794)
			(stroke
				(width 0.1)
				(type default)
			)
			(layer "B.Fab")
		)
		(fp_line
			(start -0.67945 0.3048)
			(end -0.120396 0.3048)
			(stroke
				(width 0.1)
				(type default)
			)
			(layer "B.Fab")
		)
		(pad "1" smd circle
			(at 0.40005 0 270)
			(size 0 0)
			(layers "B.Cu" "B.Mask" "B.Paste")
			(net "P0V9_CPU0_RT1_2A")
		)
		(pad "2" smd circle
			(at -0.40005 0 270)
			(size 0 0)
			(layers "B.Cu" "B.Mask" "B.Paste")
			(net "GND")
		)
	)
)
